(kicad_pcb
	(version 20260206)
	(generator "pcbnew")
	(generator_version "10.0")
	(general
		(thickness 1.6)
		(legacy_teardrops no)
	)
	(paper "A4")
	(title_block
		(title "03242023_DA0F0TMBIJ0_F0T_Motherboard_J_brd_V01_OCP.brd")
		(comment 1 "Grand Teton / footprint 1354 of 6105 (J30), pads 113-224 of 291")
	)
	(layers
		(0 "F.Cu" signal "TOP")
		(4 "In1.Cu" signal "GND")
		(6 "In2.Cu" signal "IN1")
		(8 "In3.Cu" signal "GND1")
		(10 "In4.Cu" signal "IN2")
		(12 "In5.Cu" signal "GND2")
		(14 "In6.Cu" signal "IN3")
		(16 "In7.Cu" signal "GND3")
		(18 "In8.Cu" signal "VCC")
		(20 "In9.Cu" signal "VCC1")
		(22 "In10.Cu" signal "GND4")
		(24 "In11.Cu" signal "IN4")
		(26 "In12.Cu" signal "GND5")
		(28 "In13.Cu" signal "IN5")
		(30 "In14.Cu" signal "GND6")
		(32 "In15.Cu" signal "IN6")
		(34 "In16.Cu" signal "GND7")
		(2 "B.Cu" signal "BOTTOM")
		(9 "F.Adhes" user "F.Adhesive")
		(11 "B.Adhes" user "B.Adhesive")
		(13 "F.Paste" user "Package Geometry/Pastemask Top")
		(15 "B.Paste" user "Package Geometry/Pastemask Bottom")
		(5 "F.SilkS" user "Ref Des/Silkscreen Top")
		(7 "B.SilkS" user "Ref Des/Silkscreen Bottom")
		(1 "F.Mask" user "Board Geometry/Soldermask Top")
		(3 "B.Mask" user "Board Geometry/Soldermask Bottom")
		(17 "Dwgs.User" user "User.Drawings")
		(19 "Cmts.User" user "User.Comments")
		(21 "Eco1.User" user "User.Eco1")
		(23 "Eco2.User" user "User.Eco2")
		(25 "Edge.Cuts" user "Board Geometry/Outline")
		(27 "Margin" user)
		(31 "F.CrtYd" user "Package Geometry/Place Bound Top")
		(29 "B.CrtYd" user "Package Geometry/Place Bound Bottom")
		(35 "F.Fab" user "Ref Des/Assembly Top")
		(33 "B.Fab" user "Ref Des/Assembly Bottom")
	)
	(footprint ""
		(layer "F.Cu")
		(at 191.03848 -258.091686)
		(property "Reference" "J30"
			(at -2.98196 -81.740248 0)
			(unlocked yes)
			(layer "F.SilkS")
			(effects
				(font
					(size 0.7874 0.5842)
					(thickness 0.1524)
				)
				(justify left)
			)
		)
		(property "Value" ""
			(at 0 0 0)
			(layer "F.Fab")
			(effects
				(font
					(size 1.27 1.27)
				)
			)
		)
		(duplicate_pad_numbers_are_jumpers no)
		(pad "113" smd rect
			(at -2.050034 36.975034 270)
			(size 0.519938 1.4986)
			(layers "F.Cu" "F.Mask" "F.Paste")
			(net "M_G_CPU1_SB_DQ<9>")
		)
		(pad "114" smd rect
			(at -2.050034 37.824918 270)
			(size 0.519938 1.4986)
			(layers "F.Cu" "F.Mask" "F.Paste")
			(net "GND")
		)
		(pad "115" smd rect
			(at -2.050034 38.675056 270)
			(size 0.519938 1.4986)
			(layers "F.Cu" "F.Mask" "F.Paste")
			(net "M_G_CPU1_SB_DQS_DP<1>")
		)
		(pad "116" smd rect
			(at -2.050034 39.52494 270)
			(size 0.519938 1.4986)
			(layers "F.Cu" "F.Mask" "F.Paste")
			(net "M_G_CPU1_SB_DQS_DN<1>")
		)
		(pad "117" smd rect
			(at -2.050034 40.375078 270)
			(size 0.519938 1.4986)
			(layers "F.Cu" "F.Mask" "F.Paste")
			(net "GND")
		)
		(pad "118" smd rect
			(at -2.050034 41.224962 270)
			(size 0.519938 1.4986)
			(layers "F.Cu" "F.Mask" "F.Paste")
			(net "M_G_CPU1_SB_DQ<12>")
		)
		(pad "119" smd rect
			(at -2.050034 42.0751 270)
			(size 0.519938 1.4986)
			(layers "F.Cu" "F.Mask" "F.Paste")
			(net "GND")
		)
		(pad "120" smd rect
			(at -2.050034 42.924984 270)
			(size 0.519938 1.4986)
			(layers "F.Cu" "F.Mask" "F.Paste")
			(net "M_G_CPU1_SB_DQ<13>")
		)
		(pad "121" smd rect
			(at -2.050034 43.775122 270)
			(size 0.519938 1.4986)
			(layers "F.Cu" "F.Mask" "F.Paste")
			(net "GND")
		)
		(pad "122" smd rect
			(at -2.050034 44.625006 270)
			(size 0.519938 1.4986)
			(layers "F.Cu" "F.Mask" "F.Paste")
			(net "M_G_CPU1_SB_DQ<16>")
		)
		(pad "123" smd rect
			(at -2.050034 45.47489 270)
			(size 0.519938 1.4986)
			(layers "F.Cu" "F.Mask" "F.Paste")
			(net "GND")
		)
		(pad "124" smd rect
			(at -2.050034 46.325028 270)
			(size 0.519938 1.4986)
			(layers "F.Cu" "F.Mask" "F.Paste")
			(net "M_G_CPU1_SB_DQ<17>")
		)
		(pad "125" smd rect
			(at -2.050034 47.174912 270)
			(size 0.519938 1.4986)
			(layers "F.Cu" "F.Mask" "F.Paste")
			(net "GND")
		)
		(pad "126" smd rect
			(at -2.050034 48.02505 270)
			(size 0.519938 1.4986)
			(layers "F.Cu" "F.Mask" "F.Paste")
			(net "M_G_CPU1_SB_DQS_DP<2>")
		)
		(pad "127" smd rect
			(at -2.050034 48.874934 270)
			(size 0.519938 1.4986)
			(layers "F.Cu" "F.Mask" "F.Paste")
			(net "M_G_CPU1_SB_DQS_DN<2>")
		)
		(pad "128" smd rect
			(at -2.050034 49.725072 270)
			(size 0.519938 1.4986)
			(layers "F.Cu" "F.Mask" "F.Paste")
			(net "GND")
		)
		(pad "129" smd rect
			(at -2.050034 50.574956 270)
			(size 0.519938 1.4986)
			(layers "F.Cu" "F.Mask" "F.Paste")
			(net "M_G_CPU1_SB_DQ<20>")
		)
		(pad "130" smd rect
			(at -2.050034 51.425094 270)
			(size 0.519938 1.4986)
			(layers "F.Cu" "F.Mask" "F.Paste")
			(net "GND")
		)
		(pad "131" smd rect
			(at -2.050034 52.274978 270)
			(size 0.519938 1.4986)
			(layers "F.Cu" "F.Mask" "F.Paste")
			(net "M_G_CPU1_SB_DQ<21>")
		)
		(pad "132" smd rect
			(at -2.050034 53.125116 270)
			(size 0.519938 1.4986)
			(layers "F.Cu" "F.Mask" "F.Paste")
			(net "GND")
		)
		(pad "133" smd rect
			(at -2.050034 53.975 270)
			(size 0.519938 1.4986)
			(layers "F.Cu" "F.Mask" "F.Paste")
			(net "M_G_CPU1_SB_DQ<24>")
		)
		(pad "134" smd rect
			(at -2.050034 54.824884 270)
			(size 0.519938 1.4986)
			(layers "F.Cu" "F.Mask" "F.Paste")
			(net "GND")
		)
		(pad "135" smd rect
			(at -2.050034 55.675022 270)
			(size 0.519938 1.4986)
			(layers "F.Cu" "F.Mask" "F.Paste")
			(net "M_G_CPU1_SB_DQ<25>")
		)
		(pad "136" smd rect
			(at -2.050034 56.524906 270)
			(size 0.519938 1.4986)
			(layers "F.Cu" "F.Mask" "F.Paste")
			(net "GND")
		)
		(pad "137" smd rect
			(at -2.050034 57.375044 270)
			(size 0.519938 1.4986)
			(layers "F.Cu" "F.Mask" "F.Paste")
			(net "M_G_CPU1_SB_DQS_DP<3>")
		)
		(pad "138" smd rect
			(at -2.050034 58.224928 270)
			(size 0.519938 1.4986)
			(layers "F.Cu" "F.Mask" "F.Paste")
			(net "M_G_CPU1_SB_DQS_DN<3>")
		)
		(pad "139" smd rect
			(at -2.050034 59.075066 270)
			(size 0.519938 1.4986)
			(layers "F.Cu" "F.Mask" "F.Paste")
			(net "GND")
		)
		(pad "140" smd rect
			(at -2.050034 59.92495 270)
			(size 0.519938 1.4986)
			(layers "F.Cu" "F.Mask" "F.Paste")
			(net "M_G_CPU1_SB_DQ<28>")
		)
		(pad "141" smd rect
			(at -2.050034 60.775088 270)
			(size 0.519938 1.4986)
			(layers "F.Cu" "F.Mask" "F.Paste")
			(net "GND")
		)
		(pad "142" smd rect
			(at -2.050034 61.624972 270)
			(size 0.519938 1.4986)
			(layers "F.Cu" "F.Mask" "F.Paste")
			(net "M_G_CPU1_SB_DQ<29>")
		)
		(pad "143" smd rect
			(at -2.050034 62.47511 270)
			(size 0.519938 1.4986)
			(layers "F.Cu" "F.Mask" "F.Paste")
			(net "GND")
		)
		(pad "144" smd rect
			(at -2.050034 63.324994 270)
			(size 0.519938 1.4986)
			(layers "F.Cu" "F.Mask" "F.Paste")
			(net "TP_CHG_CPU1_DIMM2_FRU_1")
		)
		(pad "145" smd rect
			(at 2.050034 -63.324994 270)
			(size 0.519938 1.4986)
			(layers "F.Cu" "F.Mask" "F.Paste")
			(net "P12V_S3_AUX_CPU1_NVDIMM")
		)
		(pad "146" smd rect
			(at 2.050034 -62.47511 270)
			(size 0.519938 1.4986)
			(layers "F.Cu" "F.Mask" "F.Paste")
			(net "P12V_S3_AUX_CPU1_NVDIMM")
		)
		(pad "147" smd rect
			(at 2.050034 -61.624972 270)
			(size 0.519938 1.4986)
			(layers "F.Cu" "F.Mask" "F.Paste")
			(net "PWRGD_CHG_CPU1_DIMM2")
		)
		(pad "148" smd rect
			(at 2.050034 -60.775088 270)
			(size 0.519938 1.4986)
			(layers "F.Cu" "F.Mask" "F.Paste")
			(net "PD_CHG_CPU1_DIMM2_SAA")
		)
		(pad "149" smd rect
			(at 2.050034 -59.92495 270)
			(size 0.519938 1.4986)
			(layers "F.Cu" "F.Mask" "F.Paste")
			(net "TP_CHG_CPU1_DIMM2_FRU_2")
		)
		(pad "150" smd rect
			(at 2.050034 -59.075066 270)
			(size 0.519938 1.4986)
			(layers "F.Cu" "F.Mask" "F.Paste")
			(net "TP_CHG_CPU1_DIMM2_FRU_3")
		)
		(pad "151" smd rect
			(at 2.050034 -58.224928 270)
			(size 0.519938 1.4986)
			(layers "F.Cu" "F.Mask" "F.Paste")
			(net "GND")
		)
		(pad "152" smd rect
			(at 2.050034 -57.375044 270)
			(size 0.519938 1.4986)
			(layers "F.Cu" "F.Mask" "F.Paste")
			(net "M_G_CPU1_SA_DQ<2>")
		)
		(pad "153" smd rect
			(at 2.050034 -56.524906 270)
			(size 0.519938 1.4986)
			(layers "F.Cu" "F.Mask" "F.Paste")
			(net "GND")
		)
		(pad "154" smd rect
			(at 2.050034 -55.675022 270)
			(size 0.519938 1.4986)
			(layers "F.Cu" "F.Mask" "F.Paste")
			(net "M_G_CPU1_SA_DQ<3>")
		)
		(pad "155" smd rect
			(at 2.050034 -54.824884 270)
			(size 0.519938 1.4986)
			(layers "F.Cu" "F.Mask" "F.Paste")
			(net "GND")
		)
		(pad "156" smd rect
			(at 2.050034 -53.975 270)
			(size 0.519938 1.4986)
			(layers "F.Cu" "F.Mask" "F.Paste")
			(net "M_G_CPU1_SA_DQS_DN<5>")
		)
		(pad "157" smd rect
			(at 2.050034 -53.125116 270)
			(size 0.519938 1.4986)
			(layers "F.Cu" "F.Mask" "F.Paste")
			(net "M_G_CPU1_SA_DQS_DP<5>")
		)
		(pad "158" smd rect
			(at 2.050034 -52.274978 270)
			(size 0.519938 1.4986)
			(layers "F.Cu" "F.Mask" "F.Paste")
			(net "GND")
		)
		(pad "159" smd rect
			(at 2.050034 -51.425094 270)
			(size 0.519938 1.4986)
			(layers "F.Cu" "F.Mask" "F.Paste")
			(net "M_G_CPU1_SA_DQ<6>")
		)
		(pad "160" smd rect
			(at 2.050034 -50.574956 270)
			(size 0.519938 1.4986)
			(layers "F.Cu" "F.Mask" "F.Paste")
			(net "GND")
		)
		(pad "161" smd rect
			(at 2.050034 -49.725072 270)
			(size 0.519938 1.4986)
			(layers "F.Cu" "F.Mask" "F.Paste")
			(net "M_G_CPU1_SA_DQ<7>")
		)
		(pad "162" smd rect
			(at 2.050034 -48.874934 270)
			(size 0.519938 1.4986)
			(layers "F.Cu" "F.Mask" "F.Paste")
			(net "GND")
		)
		(pad "163" smd rect
			(at 2.050034 -48.02505 270)
			(size 0.519938 1.4986)
			(layers "F.Cu" "F.Mask" "F.Paste")
			(net "M_G_CPU1_SA_DQ<10>")
		)
		(pad "164" smd rect
			(at 2.050034 -47.174912 270)
			(size 0.519938 1.4986)
			(layers "F.Cu" "F.Mask" "F.Paste")
			(net "GND")
		)
		(pad "165" smd rect
			(at 2.050034 -46.325028 270)
			(size 0.519938 1.4986)
			(layers "F.Cu" "F.Mask" "F.Paste")
			(net "M_G_CPU1_SA_DQ<11>")
		)
		(pad "166" smd rect
			(at 2.050034 -45.47489 270)
			(size 0.519938 1.4986)
			(layers "F.Cu" "F.Mask" "F.Paste")
			(net "GND")
		)
		(pad "167" smd rect
			(at 2.050034 -44.625006 270)
			(size 0.519938 1.4986)
			(layers "F.Cu" "F.Mask" "F.Paste")
			(net "M_G_CPU1_SA_DQS_DN<6>")
		)
		(pad "168" smd rect
			(at 2.050034 -43.775122 270)
			(size 0.519938 1.4986)
			(layers "F.Cu" "F.Mask" "F.Paste")
			(net "M_G_CPU1_SA_DQS_DP<6>")
		)
		(pad "169" smd rect
			(at 2.050034 -42.924984 270)
			(size 0.519938 1.4986)
			(layers "F.Cu" "F.Mask" "F.Paste")
			(net "GND")
		)
		(pad "170" smd rect
			(at 2.050034 -42.0751 270)
			(size 0.519938 1.4986)
			(layers "F.Cu" "F.Mask" "F.Paste")
			(net "M_G_CPU1_SA_DQ<14>")
		)
		(pad "171" smd rect
			(at 2.050034 -41.224962 270)
			(size 0.519938 1.4986)
			(layers "F.Cu" "F.Mask" "F.Paste")
			(net "GND")
		)
		(pad "172" smd rect
			(at 2.050034 -40.375078 270)
			(size 0.519938 1.4986)
			(layers "F.Cu" "F.Mask" "F.Paste")
			(net "M_G_CPU1_SA_DQ<15>")
		)
		(pad "173" smd rect
			(at 2.050034 -39.52494 270)
			(size 0.519938 1.4986)
			(layers "F.Cu" "F.Mask" "F.Paste")
			(net "GND")
		)
		(pad "174" smd rect
			(at 2.050034 -38.675056 270)
			(size 0.519938 1.4986)
			(layers "F.Cu" "F.Mask" "F.Paste")
			(net "M_G_CPU1_SA_DQ<18>")
		)
		(pad "175" smd rect
			(at 2.050034 -37.824918 270)
			(size 0.519938 1.4986)
			(layers "F.Cu" "F.Mask" "F.Paste")
			(net "GND")
		)
		(pad "176" smd rect
			(at 2.050034 -36.975034 270)
			(size 0.519938 1.4986)
			(layers "F.Cu" "F.Mask" "F.Paste")
			(net "M_G_CPU1_SA_DQ<19>")
		)
		(pad "177" smd rect
			(at 2.050034 -36.124896 270)
			(size 0.519938 1.4986)
			(layers "F.Cu" "F.Mask" "F.Paste")
			(net "GND")
		)
		(pad "178" smd rect
			(at 2.050034 -35.275012 270)
			(size 0.519938 1.4986)
			(layers "F.Cu" "F.Mask" "F.Paste")
			(net "M_G_CPU1_SA_DQS_DN<7>")
		)
		(pad "179" smd rect
			(at 2.050034 -34.425128 270)
			(size 0.519938 1.4986)
			(layers "F.Cu" "F.Mask" "F.Paste")
			(net "M_G_CPU1_SA_DQS_DP<7>")
		)
		(pad "180" smd rect
			(at 2.050034 -33.57499 270)
			(size 0.519938 1.4986)
			(layers "F.Cu" "F.Mask" "F.Paste")
			(net "GND")
		)
		(pad "181" smd rect
			(at 2.050034 -32.725106 270)
			(size 0.519938 1.4986)
			(layers "F.Cu" "F.Mask" "F.Paste")
			(net "M_G_CPU1_SA_DQ<22>")
		)
		(pad "182" smd rect
			(at 2.050034 -31.874968 270)
			(size 0.519938 1.4986)
			(layers "F.Cu" "F.Mask" "F.Paste")
			(net "GND")
		)
		(pad "183" smd rect
			(at 2.050034 -31.025084 270)
			(size 0.519938 1.4986)
			(layers "F.Cu" "F.Mask" "F.Paste")
			(net "M_G_CPU1_SA_DQ<23>")
		)
		(pad "184" smd rect
			(at 2.050034 -30.174946 270)
			(size 0.519938 1.4986)
			(layers "F.Cu" "F.Mask" "F.Paste")
			(net "GND")
		)
		(pad "185" smd rect
			(at 2.050034 -29.325062 270)
			(size 0.519938 1.4986)
			(layers "F.Cu" "F.Mask" "F.Paste")
			(net "M_G_CPU1_SA_DQ<26>")
		)
		(pad "186" smd rect
			(at 2.050034 -28.474924 270)
			(size 0.519938 1.4986)
			(layers "F.Cu" "F.Mask" "F.Paste")
			(net "GND")
		)
		(pad "187" smd rect
			(at 2.050034 -27.62504 270)
			(size 0.519938 1.4986)
			(layers "F.Cu" "F.Mask" "F.Paste")
			(net "M_G_CPU1_SA_DQ<27>")
		)
		(pad "188" smd rect
			(at 2.050034 -26.774902 270)
			(size 0.519938 1.4986)
			(layers "F.Cu" "F.Mask" "F.Paste")
			(net "GND")
		)
		(pad "189" smd rect
			(at 2.050034 -25.925018 270)
			(size 0.519938 1.4986)
			(layers "F.Cu" "F.Mask" "F.Paste")
			(net "M_G_CPU1_SA_DQS_DN<8>")
		)
		(pad "190" smd rect
			(at 2.050034 -25.07488 270)
			(size 0.519938 1.4986)
			(layers "F.Cu" "F.Mask" "F.Paste")
			(net "M_G_CPU1_SA_DQS_DP<8>")
		)
		(pad "191" smd rect
			(at 2.050034 -24.224996 270)
			(size 0.519938 1.4986)
			(layers "F.Cu" "F.Mask" "F.Paste")
			(net "GND")
		)
		(pad "192" smd rect
			(at 2.050034 -23.375112 270)
			(size 0.519938 1.4986)
			(layers "F.Cu" "F.Mask" "F.Paste")
			(net "M_G_CPU1_SA_DQ<30>")
		)
		(pad "193" smd rect
			(at 2.050034 -22.524974 270)
			(size 0.519938 1.4986)
			(layers "F.Cu" "F.Mask" "F.Paste")
			(net "GND")
		)
		(pad "194" smd rect
			(at 2.050034 -21.67509 270)
			(size 0.519938 1.4986)
			(layers "F.Cu" "F.Mask" "F.Paste")
			(net "M_G_CPU1_SA_DQ<31>")
		)
		(pad "195" smd rect
			(at 2.050034 -20.824952 270)
			(size 0.519938 1.4986)
			(layers "F.Cu" "F.Mask" "F.Paste")
			(net "GND")
		)
		(pad "196" smd rect
			(at 2.050034 -19.975068 270)
			(size 0.519938 1.4986)
			(layers "F.Cu" "F.Mask" "F.Paste")
			(net "M_G_CPU1_SA_CB<2>")
		)
		(pad "197" smd rect
			(at 2.050034 -19.12493 270)
			(size 0.519938 1.4986)
			(layers "F.Cu" "F.Mask" "F.Paste")
			(net "GND")
		)
		(pad "198" smd rect
			(at 2.050034 -18.275046 270)
			(size 0.519938 1.4986)
			(layers "F.Cu" "F.Mask" "F.Paste")
			(net "M_G_CPU1_SA_CB<3>")
		)
		(pad "199" smd rect
			(at 2.050034 -17.424908 270)
			(size 0.519938 1.4986)
			(layers "F.Cu" "F.Mask" "F.Paste")
			(net "GND")
		)
		(pad "200" smd rect
			(at 2.050034 -16.575024 270)
			(size 0.519938 1.4986)
			(layers "F.Cu" "F.Mask" "F.Paste")
			(net "M_G_CPU1_SA_DQS_DN<9>")
		)
		(pad "201" smd rect
			(at 2.050034 -15.724886 270)
			(size 0.519938 1.4986)
			(layers "F.Cu" "F.Mask" "F.Paste")
			(net "M_G_CPU1_SA_DQS_DP<9>")
		)
		(pad "202" smd rect
			(at 2.050034 -14.875002 270)
			(size 0.519938 1.4986)
			(layers "F.Cu" "F.Mask" "F.Paste")
			(net "GND")
		)
		(pad "203" smd rect
			(at 2.050034 -14.025118 270)
			(size 0.519938 1.4986)
			(layers "F.Cu" "F.Mask" "F.Paste")
			(net "M_G_CPU1_SA_CB<6>")
		)
		(pad "204" smd rect
			(at 2.050034 -13.17498 270)
			(size 0.519938 1.4986)
			(layers "F.Cu" "F.Mask" "F.Paste")
			(net "GND")
		)
		(pad "205" smd rect
			(at 2.050034 -12.325096 270)
			(size 0.519938 1.4986)
			(layers "F.Cu" "F.Mask" "F.Paste")
			(net "M_G_CPU1_SA_CB<7>")
		)
		(pad "206" smd rect
			(at 2.050034 -11.474958 270)
			(size 0.519938 1.4986)
			(layers "F.Cu" "F.Mask" "F.Paste")
			(net "GND")
		)
		(pad "207" smd rect
			(at 2.050034 -10.625074 270)
			(size 0.519938 1.4986)
			(layers "F.Cu" "F.Mask" "F.Paste")
			(net "RST_M_GH_CPU1_FPGA_N")
		)
		(pad "208" smd rect
			(at 2.050034 -9.774936 270)
			(size 0.519938 1.4986)
			(layers "F.Cu" "F.Mask" "F.Paste")
			(net "GND")
		)
		(pad "209" smd rect
			(at 2.050034 -8.925052 270)
			(size 0.519938 1.4986)
			(layers "F.Cu" "F.Mask" "F.Paste")
			(net "M_G_CPU1_SA_CS_N<3>")
		)
		(pad "210" smd rect
			(at 2.050034 -8.074914 270)
			(size 0.519938 1.4986)
			(layers "F.Cu" "F.Mask" "F.Paste")
			(net "GND")
		)
		(pad "211" smd rect
			(at 2.050034 -7.22503 270)
			(size 0.519938 1.4986)
			(layers "F.Cu" "F.Mask" "F.Paste")
			(net "M_G_CPU1_SA_CA<1>")
		)
		(pad "212" smd rect
			(at 2.050034 -6.374892 270)
			(size 0.519938 1.4986)
			(layers "F.Cu" "F.Mask" "F.Paste")
			(net "GND")
		)
		(pad "213" smd rect
			(at 2.050034 -5.525008 270)
			(size 0.519938 1.4986)
			(layers "F.Cu" "F.Mask" "F.Paste")
			(net "M_G_CPU1_SA_CA<3>")
		)
		(pad "214" smd rect
			(at 2.050034 -4.675124 270)
			(size 0.519938 1.4986)
			(layers "F.Cu" "F.Mask" "F.Paste")
			(net "GND")
		)
		(pad "215" smd rect
			(at 2.050034 -3.824986 270)
			(size 0.519938 1.4986)
			(layers "F.Cu" "F.Mask" "F.Paste")
			(net "M_G_CPU1_SA_CA<5>")
		)
		(pad "216" smd rect
			(at 2.050034 -2.975102 270)
			(size 0.519938 1.4986)
			(layers "F.Cu" "F.Mask" "F.Paste")
			(net "GND")
		)
		(pad "217" smd rect
			(at 2.050034 -2.124964 270)
			(size 0.519938 1.4986)
			(layers "F.Cu" "F.Mask" "F.Paste")
			(net "M_G_CPU1_CLK_DP<1>")
		)
		(pad "218" smd rect
			(at 2.050034 -1.27508 270)
			(size 0.519938 1.4986)
			(layers "F.Cu" "F.Mask" "F.Paste")
			(net "M_G_CPU1_CLK_DN<1>")
		)
		(pad "219" smd rect
			(at 2.050034 -0.424942 270)
			(size 0.519938 1.4986)
			(layers "F.Cu" "F.Mask" "F.Paste")
			(net "GND")
		)
		(pad "220" smd rect
			(at 2.050034 5.525008 270)
			(size 0.519938 1.4986)
			(layers "F.Cu" "F.Mask" "F.Paste")
			(net "TP_CHG_CPU1_DIMM2_FRU_4")
		)
		(pad "221" smd rect
			(at 2.050034 6.374892 270)
			(size 0.519938 1.4986)
			(layers "F.Cu" "F.Mask" "F.Paste")
			(net "M_G_CPU1_SB_CA<1>")
		)
		(pad "222" smd rect
			(at 2.050034 7.22503 270)
			(size 0.519938 1.4986)
			(layers "F.Cu" "F.Mask" "F.Paste")
			(net "GND")
		)
		(pad "223" smd rect
			(at 2.050034 8.074914 270)
			(size 0.519938 1.4986)
			(layers "F.Cu" "F.Mask" "F.Paste")
			(net "M_G_CPU1_SB_CA<3>")
		)
		(pad "224" smd rect
			(at 2.050034 8.925052 270)
			(size 0.519938 1.4986)
			(layers "F.Cu" "F.Mask" "F.Paste")
			(net "GND")
		)
	)
)
